FILE_TYPE = MULTI_PHYS_TABLE;

PART '74LVC1G07W57'

{========================================================================================}
:VALUE           | PART_TYPE | MATERIAL | PART_NUMBER    = STANDARD    | LIFECYCLE     | PART_NUMBER   | JEDEC_TYPE           | DESCRIPTION                  | MANUFTR | MANUF_PN        | RD_CMPLS_LVL | CMPLS_LVL | FROM_PJ   | CLASS | DIP_SMD | DATA                    | EE_CHECK_LIST | FP_ECN | PSL | CREATOR | STATUS | MSD | ESD_CDM | ESD_HBM | ESD_MM | PIN_LENGTH_SHORT_PIN | PIN_LENGTH_LONG_PIN | CREATEDAY  ;
{========================================================================================}
 '74LVC1G07W5-7' | 'SMLF'    | 'IC'     | 'ALVC1G07001'(!) = ''               | ''               | 'ALVC1G07001' |'SOT25-5_0-95_3X1-6'| 'IC(5P)74LVC1G07W5-7(SOT25)' | 'DDS'   | '74LVC1G07W5-7' | 'EP(V1)'     | ''        | 'A5G-LEO' | 'IC'  | ''      | 'DDS_74LVC1G07W5-7.pdf' | ''            | ''     | ''  | ''      | ''     | ''  | ''      | ''      | ''     | '0 MILS'             | '0 MILS'            | '20210622'
 '74LVC1G07W5-7' | 'SMLF'    | 'EMPTY'  | 'ALVC1G07001'(!) = ''               | ''               | 'ALVC1G07001' |'SOT25-5_0-95_3X1-6'| 'IC(5P)74LVC1G07W5-7(SOT25)' | 'DDS'   | '74LVC1G07W5-7' | 'EP(V1)'     | ''        | 'A5G-LEO' | 'IC'  | ''      | 'DDS_74LVC1G07W5-7.pdf' | ''            | ''     | ''  | ''      | ''     | ''  | ''      | ''      | ''     | '0 MILS'             | '0 MILS'            | '20210622'

END_PART

END.

